# T6G (Grand Teton) — schematic netlist excerpt (pin names and nets, part order shuffled) for the footprints in the layout excerpt that follows; sources: Cadence DE-HDL packaged netlist, KiCad conversion of 04192023_DAF0TMB3IC0_F0TG_MB_C_brd_V02_OCP.brd

Q132  MOSFET_NCH_DUAL  PJT138K IC  pkg SOT363XD  page 125
  S1  = GND
  G1  = PRSNT_CABLE_GPU_B3_N
  D2  = PRSNT_CABLE_GPU_B3_ISO_N
  S2  = GND
  G2  = PRSNT_CABLE_GPU_B3
  D1  = PRSNT_CABLE_GPU_B3

R107  Q_RES  1K 1% EMPTY  pkg 0402LF  page 102 : A = P3V3 ; B = PWRGD_CHE_CPU1_DIMM
C610  Q_CAP  0.1UF 10V 10% X7S  pkg C0201  page 290 : A = P0V9_CPU0_RT_2D ; B = GND

(kicad_pcb
	(version 20260206)
	(generator "pcbnew")
	(generator_version "10.0")
	(general
		(thickness 1.6)
		(legacy_teardrops no)
	)
	(paper "A4")
	(title_block
		(title "04192023_DAF0TMB3IC0_F0TG_MB_C_brd_V02_OCP.brd")
		(comment 1 "Grand Teton / footprints 7567-7569 of 8354")
	)
	(layers
		(0 "F.Cu" signal "TOP")
		(4 "In1.Cu" signal "GND")
		(6 "In2.Cu" signal "IN1")
		(8 "In3.Cu" signal "GND1")
		(10 "In4.Cu" signal "IN2")
		(12 "In5.Cu" signal "GND2")
		(14 "In6.Cu" signal "IN3")
		(16 "In7.Cu" signal "GND3")
		(18 "In8.Cu" signal "VCC")
		(20 "In9.Cu" signal "VCC1")
		(22 "In10.Cu" signal "GND4")
		(24 "In11.Cu" signal "IN4")
		(26 "In12.Cu" signal "GND5")
		(28 "In13.Cu" signal "IN5")
		(30 "In14.Cu" signal "GND6")
		(32 "In15.Cu" signal "IN6")
		(34 "In16.Cu" signal "GND7")
		(2 "B.Cu" signal "BOTTOM")
		(9 "F.Adhes" user "F.Adhesive")
		(11 "B.Adhes" user "B.Adhesive")
		(13 "F.Paste" user "Package Geometry/Pastemask Top")
		(15 "B.Paste" user "Package Geometry/Pastemask Bottom")
		(5 "F.SilkS" user "Ref Des/Silkscreen Top")
		(7 "B.SilkS" user "Ref Des/Silkscreen Bottom")
		(1 "F.Mask" user "Board Geometry/Soldermask Top")
		(3 "B.Mask" user "Board Geometry/Soldermask Bottom")
		(17 "Dwgs.User" user "User.Drawings")
		(19 "Cmts.User" user "User.Comments")
		(21 "Eco1.User" user "User.Eco1")
		(23 "Eco2.User" user "User.Eco2")
		(25 "Edge.Cuts" user "Board Geometry/Outline")
		(27 "Margin" user)
		(31 "F.CrtYd" user "Package Geometry/Place Bound Top")
		(29 "B.CrtYd" user "Package Geometry/Place Bound Bottom")
		(35 "F.Fab" user "Ref Des/Assembly Top")
		(33 "B.Fab" user "Ref Des/Assembly Bottom")
	)
	(footprint ""
		(layer "B.Cu")
		(at 341.906098 -395.148562 90)
		(property "Reference" "C610"
			(at 0 0 90)
			(layer "B.SilkS")
			(hide yes)
			(effects
				(font
					(size 1.27 1.27)
				)
				(justify mirror)
			)
		)
		(property "Value" ""
			(at 0 0 90)
			(layer "B.Fab")
			(effects
				(font
					(size 1.27 1.27)
				)
				(justify mirror)
			)
		)
		(duplicate_pad_numbers_are_jumpers no)
		(fp_line
			(start 0.299974 -0.150114)
			(end -0.299974 -0.150114)
			(stroke
				(width 0.1)
				(type default)
			)
			(layer "B.Fab")
		)
		(fp_line
			(start -0.299974 -0.150114)
			(end -0.299974 0.150114)
			(stroke
				(width 0.1)
				(type default)
			)
			(layer "B.Fab")
		)
		(fp_line
			(start 0.299974 0.150114)
			(end 0.299974 -0.150114)
			(stroke
				(width 0.1)
				(type default)
			)
			(layer "B.Fab")
		)
		(fp_line
			(start -0.299974 0.150114)
			(end 0.299974 0.150114)
			(stroke
				(width 0.1)
				(type default)
			)
			(layer "B.Fab")
		)
		(pad "1" smd rect
			(at 0.2667 0 270)
			(size 0.3048 0.381)
			(layers "B.Cu" "B.Mask" "B.Paste")
			(net "P0V9_CPU0_RT_2D")
		)
		(pad "2" smd rect
			(at -0.2667 0 270)
			(size 0.3048 0.381)
			(layers "B.Cu" "B.Mask" "B.Paste")
			(net "GND")
		)
	)
	(footprint ""
		(layer "B.Cu")
		(at 167.502332 -434.882544 180)
		(property "Reference" "Q132"
			(at -5.782056 0.352552 0)
			(unlocked yes)
			(layer "B.SilkS")
			(effects
				(font
					(size 0.7874 0.5842)
					(thickness 0.1524)
				)
				(justify left mirror)
			)
		)
		(property "Value" ""
			(at 0 0 0)
			(layer "B.Fab")
			(effects
				(font
					(size 1.27 1.27)
				)
				(justify mirror)
			)
		)
		(duplicate_pad_numbers_are_jumpers no)
		(fp_line
			(start 1.332738 1.100074)
			(end 1.332738 -1.100074)
			(stroke
				(width 0.1524)
				(type default)
			)
			(layer "B.SilkS")
		)
		(fp_line
			(start 1.332738 -1.100074)
			(end 0.4826 -1.100074)
			(stroke
				(width 0.1524)
				(type default)
			)
			(layer "B.SilkS")
		)
		(fp_line
			(start 0.4826 -1.100074)
			(end 0 -0.541274)
			(stroke
				(width 0.1524)
				(type default)
			)
			(layer "B.SilkS")
		)
		(fp_line
			(start 0 -0.541274)
			(end -0.4826 -1.100074)
			(stroke
				(width 0.1524)
				(type default)
			)
			(layer "B.SilkS")
		)
		(fp_line
			(start -0.4826 -1.100074)
			(end -1.332738 -1.100074)
			(stroke
				(width 0.1524)
				(type default)
			)
			(layer "B.SilkS")
		)
		(fp_line
			(start -1.332738 1.100074)
			(end 1.332738 1.100074)
			(stroke
				(width 0.1524)
				(type default)
			)
			(layer "B.SilkS")
		)
		(fp_line
			(start -1.332738 -1.100074)
			(end -1.332738 1.100074)
			(stroke
				(width 0.1524)
				(type default)
			)
			(layer "B.SilkS")
		)
		(fp_poly
			(pts
				(xy 1.020064 -1.309624) (xy 1.371092 -2.011426) (xy 0.669036 -2.011426)
			)
			(stroke
				(width 0)
				(type default)
			)
			(fill yes)
			(layer "B.SilkS")
		)
		(fp_line
			(start 0.674878 1.100074)
			(end 0.674878 -1.100074)
			(stroke
				(width 0.1)
				(type default)
			)
			(layer "B.Fab")
		)
		(fp_line
			(start 0.674878 -1.100074)
			(end -0.674878 -1.100074)
			(stroke
				(width 0.1)
				(type default)
			)
			(layer "B.Fab")
		)
		(fp_line
			(start -0.674878 1.100074)
			(end 0.674878 1.100074)
			(stroke
				(width 0.1)
				(type default)
			)
			(layer "B.Fab")
		)
		(fp_line
			(start -0.674878 -1.100074)
			(end -0.674878 1.100074)
			(stroke
				(width 0.1)
				(type default)
			)
			(layer "B.Fab")
		)
		(fp_poly
			(pts
				(xy 2.2352 -0.298958) (xy 2.2352 -1.001014) (xy 1.533144 -0.649986)
			)
			(stroke
				(width 0)
				(type default)
			)
			(fill yes)
			(layer "B.Fab")
		)
		(pad "1" smd rect
			(at 0.94996 -0.649986 270)
			(size 0.4318 0.508)
			(layers "B.Cu" "B.Mask" "B.Paste")
			(net "GND")
		)
		(pad "2" smd rect
			(at 0.94996 0 270)
			(size 0.4318 0.508)
			(layers "B.Cu" "B.Mask" "B.Paste")
			(net "PRSNT_CABLE_GPU_B3_N")
		)
		(pad "3" smd rect
			(at 0.94996 0.649986 270)
			(size 0.4318 0.508)
			(layers "B.Cu" "B.Mask" "B.Paste")
			(net "PRSNT_CABLE_GPU_B3_ISO_N")
		)
		(pad "4" smd rect
			(at -0.94996 0.649986 270)
			(size 0.4318 0.508)
			(layers "B.Cu" "B.Mask" "B.Paste")
			(net "GND")
		)
		(pad "5" smd rect
			(at -0.94996 0 270)
			(size 0.4318 0.508)
			(layers "B.Cu" "B.Mask" "B.Paste")
			(net "PRSNT_CABLE_GPU_B3")
		)
		(pad "6" smd rect
			(at -0.94996 -0.649986 270)
			(size 0.4318 0.508)
			(layers "B.Cu" "B.Mask" "B.Paste")
			(net "PRSNT_CABLE_GPU_B3")
		)
	)
	(footprint ""
		(layer "B.Cu")
		(at 25.92324 -193.996564)
		(property "Reference" "R107"
			(at 0 0 0)
			(layer "B.SilkS")
			(hide yes)
			(effects
				(font
					(size 1.27 1.27)
				)
				(justify mirror)
			)
		)
		(property "Value" ""
			(at 0 0 0)
			(layer "B.Fab")
			(effects
				(font
					(size 1.27 1.27)
				)
				(justify mirror)
			)
		)
		(duplicate_pad_numbers_are_jumpers no)
		(fp_line
			(start -0.7874 -0.4064)
			(end -0.7874 0.4064)
			(stroke
				(width 0.1524)
				(type default)
			)
			(layer "B.SilkS")
		)
		(fp_line
			(start -0.7874 0.4064)
			(end 0.7874 0.4064)
			(stroke
				(width 0.1524)
				(type default)
			)
			(layer "B.SilkS")
		)
		(fp_line
			(start 0.7874 -0.4064)
			(end -0.7874 -0.4064)
			(stroke
				(width 0.1524)
				(type default)
			)
			(layer "B.SilkS")
		)
		(fp_line
			(start 0.7874 0.4064)
			(end 0.7874 -0.4064)
			(stroke
				(width 0.1524)
				(type default)
			)
			(layer "B.SilkS")
		)
		(fp_line
			(start -0.67945 -0.3048)
			(end -0.67945 0.3048)
			(stroke
				(width 0.1)
				(type default)
			)
			(layer "B.Fab")
		)
		(fp_line
			(start -0.67945 0.3048)
			(end -0.120396 0.3048)
			(stroke
				(width 0.1)
				(type default)
			)
			(layer "B.Fab")
		)
		(fp_line
			(start -0.12065 -0.3048)
			(end -0.67945 -0.3048)
			(stroke
				(width 0.1)
				(type default)
			)
			(layer "B.Fab")
		)
		(fp_line
			(start -0.12065 -0.2794)
			(end -0.12065 -0.3048)
			(stroke
				(width 0.1)
				(type default)
			)
			(layer "B.Fab")
		)
		(fp_line
			(start -0.120396 0.2794)
			(end 0.12065 0.2794)
			(stroke
				(width 0.1)
				(type default)
			)
			(layer "B.Fab")
		)
		(fp_line
			(start -0.120396 0.3048)
			(end -0.120396 0.2794)
			(stroke
				(width 0.1)
				(type default)
			)
			(layer "B.Fab")
		)
		(fp_line
			(start 0.12065 -0.305054)
			(end 0.12065 -0.2794)
			(stroke
				(width 0.1)
				(type default)
			)
			(layer "B.Fab")
		)
		(fp_line
			(start 0.12065 -0.2794)
			(end -0.12065 -0.2794)
			(stroke
				(width 0.1)
				(type default)
			)
			(layer "B.Fab")
		)
		(fp_line
			(start 0.12065 0.2794)
			(end 0.12065 0.3048)
			(stroke
				(width 0.1)
				(type default)
			)
			(layer "B.Fab")
		)
		(fp_line
			(start 0.12065 0.3048)
			(end 0.67945 0.3048)
			(stroke
				(width 0.1)
				(type default)
			)
			(layer "B.Fab")
		)
		(fp_line
			(start 0.67945 -0.305054)
			(end 0.12065 -0.305054)
			(stroke
				(width 0.1)
				(type default)
			)
			(layer "B.Fab")
		)
		(fp_line
			(start 0.67945 0.3048)
			(end 0.67945 -0.305054)
			(stroke
				(width 0.1)
				(type default)
			)
			(layer "B.Fab")
		)
		(pad "1" smd circle
			(at 0.40005 0 180)
			(size 0 0)
			(layers "B.Cu" "B.Mask" "B.Paste")
			(net "P3V3")
		)
		(pad "2" smd circle
			(at -0.40005 0 180)
			(size 0 0)
			(layers "B.Cu" "B.Mask" "B.Paste")
			(net "PWRGD_CHE_CPU1_DIMM")
		)
	)
)
